(kicad_pcb
	(version 20260206)
	(generator "pcbnew")
	(generator_version "10.0")
	(general
		(thickness 1.6)
		(legacy_teardrops no)
	)
	(paper "A4")
	(title_block
		(title "9052_F0T_PDB_Converter_Brick_F_V03_1208_1600_OCP.brd")
		(comment 1 "Grand Teton / footprints 565-571 of 578")
	)
	(layers
		(0 "F.Cu" signal "TOP")
		(4 "In1.Cu" signal "GND")
		(6 "In2.Cu" signal "IN1")
		(8 "In3.Cu" signal "GND1")
		(10 "In4.Cu" signal "VCC")
		(12 "In5.Cu" signal "VCC1")
		(14 "In6.Cu" signal "GND2")
		(16 "In7.Cu" signal "IN2")
		(18 "In8.Cu" signal "GND3")
		(2 "B.Cu" signal "BOTTOM")
		(9 "F.Adhes" user "F.Adhesive")
		(11 "B.Adhes" user "B.Adhesive")
		(13 "F.Paste" user "Package Geometry/Pastemask Top")
		(15 "B.Paste" user "Package Geometry/Pastemask Bottom")
		(5 "F.SilkS" user "Ref Des/Silkscreen Top")
		(7 "B.SilkS" user "Ref Des/Silkscreen Bottom")
		(1 "F.Mask" user "Board Geometry/Soldermask Top")
		(3 "B.Mask" user "Board Geometry/Soldermask Bottom")
		(17 "Dwgs.User" user "User.Drawings")
		(19 "Cmts.User" user "User.Comments")
		(21 "Eco1.User" user "User.Eco1")
		(23 "Eco2.User" user "User.Eco2")
		(25 "Edge.Cuts" user "Board Geometry/Outline")
		(27 "Margin" user)
		(31 "F.CrtYd" user "Package Geometry/Place Bound Top")
		(29 "B.CrtYd" user "Package Geometry/Place Bound Bottom")
		(35 "F.Fab" user "Ref Des/Assembly Top")
		(33 "B.Fab" user "Ref Des/Assembly Bottom")
	)
	(footprint ""
		(layer "B.Cu")
		(at 202.946 -91.948)
		(property "Reference" "R98"
			(at 0 0 0)
			(layer "B.SilkS")
			(hide yes)
			(effects
				(font
					(size 1.27 1.27)
				)
				(justify mirror)
			)
		)
		(property "Value" ""
			(at 0 0 0)
			(layer "B.Fab")
			(effects
				(font
					(size 1.27 1.27)
				)
				(justify mirror)
			)
		)
		(duplicate_pad_numbers_are_jumpers no)
		(fp_line
			(start -0.7874 -0.4064)
			(end -0.7874 0.4064)
			(stroke
				(width 0.1524)
				(type default)
			)
			(layer "B.SilkS")
		)
		(fp_line
			(start -0.7874 0.4064)
			(end 0.7874 0.4064)
			(stroke
				(width 0.1524)
				(type default)
			)
			(layer "B.SilkS")
		)
		(fp_line
			(start 0.7874 -0.4064)
			(end -0.7874 -0.4064)
			(stroke
				(width 0.1524)
				(type default)
			)
			(layer "B.SilkS")
		)
		(fp_line
			(start 0.7874 0.4064)
			(end 0.7874 -0.4064)
			(stroke
				(width 0.1524)
				(type default)
			)
			(layer "B.SilkS")
		)
		(fp_line
			(start -0.67945 -0.3048)
			(end -0.67945 0.3048)
			(stroke
				(width 0.1)
				(type default)
			)
			(layer "B.Fab")
		)
		(fp_line
			(start -0.67945 0.3048)
			(end -0.120396 0.3048)
			(stroke
				(width 0.1)
				(type default)
			)
			(layer "B.Fab")
		)
		(fp_line
			(start -0.12065 -0.3048)
			(end -0.67945 -0.3048)
			(stroke
				(width 0.1)
				(type default)
			)
			(layer "B.Fab")
		)
		(fp_line
			(start -0.12065 -0.2794)
			(end -0.12065 -0.3048)
			(stroke
				(width 0.1)
				(type default)
			)
			(layer "B.Fab")
		)
		(fp_line
			(start -0.120396 0.2794)
			(end 0.12065 0.2794)
			(stroke
				(width 0.1)
				(type default)
			)
			(layer "B.Fab")
		)
		(fp_line
			(start -0.120396 0.3048)
			(end -0.120396 0.2794)
			(stroke
				(width 0.1)
				(type default)
			)
			(layer "B.Fab")
		)
		(fp_line
			(start 0.12065 -0.305054)
			(end 0.12065 -0.2794)
			(stroke
				(width 0.1)
				(type default)
			)
			(layer "B.Fab")
		)
		(fp_line
			(start 0.12065 -0.2794)
			(end -0.12065 -0.2794)
			(stroke
				(width 0.1)
				(type default)
			)
			(layer "B.Fab")
		)
		(fp_line
			(start 0.12065 0.2794)
			(end 0.12065 0.3048)
			(stroke
				(width 0.1)
				(type default)
			)
			(layer "B.Fab")
		)
		(fp_line
			(start 0.12065 0.3048)
			(end 0.67945 0.3048)
			(stroke
				(width 0.1)
				(type default)
			)
			(layer "B.Fab")
		)
		(fp_line
			(start 0.67945 -0.305054)
			(end 0.12065 -0.305054)
			(stroke
				(width 0.1)
				(type default)
			)
			(layer "B.Fab")
		)
		(fp_line
			(start 0.67945 0.3048)
			(end 0.67945 -0.305054)
			(stroke
				(width 0.1)
				(type default)
			)
			(layer "B.Fab")
		)
		(pad "1" smd circle
			(at 0.40005 0 180)
			(size 0 0)
			(layers "B.Cu" "B.Mask" "B.Paste")
			(net "P3V3_AUX")
		)
		(pad "2" smd circle
			(at -0.40005 0 180)
			(size 0 0)
			(layers "B.Cu" "B.Mask" "B.Paste")
			(net "PCA9543_MISC_A0")
		)
	)
	(footprint ""
		(layer "B.Cu")
		(at 202.946 -83.82 180)
		(property "Reference" "R129"
			(at 0 0 0)
			(layer "B.SilkS")
			(hide yes)
			(effects
				(font
					(size 1.27 1.27)
				)
				(justify mirror)
			)
		)
		(property "Value" ""
			(at 0 0 0)
			(layer "B.Fab")
			(effects
				(font
					(size 1.27 1.27)
				)
				(justify mirror)
			)
		)
		(duplicate_pad_numbers_are_jumpers no)
		(fp_line
			(start 0.7874 0.4064)
			(end 0.7874 -0.4064)
			(stroke
				(width 0.1524)
				(type default)
			)
			(layer "B.SilkS")
		)
		(fp_line
			(start 0.7874 -0.4064)
			(end -0.7874 -0.4064)
			(stroke
				(width 0.1524)
				(type default)
			)
			(layer "B.SilkS")
		)
		(fp_line
			(start -0.7874 0.4064)
			(end 0.7874 0.4064)
			(stroke
				(width 0.1524)
				(type default)
			)
			(layer "B.SilkS")
		)
		(fp_line
			(start -0.7874 -0.4064)
			(end -0.7874 0.4064)
			(stroke
				(width 0.1524)
				(type default)
			)
			(layer "B.SilkS")
		)
		(fp_line
			(start 0.67945 0.3048)
			(end 0.67945 -0.305054)
			(stroke
				(width 0.1)
				(type default)
			)
			(layer "B.Fab")
		)
		(fp_line
			(start 0.67945 -0.305054)
			(end 0.12065 -0.305054)
			(stroke
				(width 0.1)
				(type default)
			)
			(layer "B.Fab")
		)
		(fp_line
			(start 0.12065 0.3048)
			(end 0.67945 0.3048)
			(stroke
				(width 0.1)
				(type default)
			)
			(layer "B.Fab")
		)
		(fp_line
			(start 0.12065 0.2794)
			(end 0.12065 0.3048)
			(stroke
				(width 0.1)
				(type default)
			)
			(layer "B.Fab")
		)
		(fp_line
			(start 0.12065 -0.2794)
			(end -0.12065 -0.2794)
			(stroke
				(width 0.1)
				(type default)
			)
			(layer "B.Fab")
		)
		(fp_line
			(start 0.12065 -0.305054)
			(end 0.12065 -0.2794)
			(stroke
				(width 0.1)
				(type default)
			)
			(layer "B.Fab")
		)
		(fp_line
			(start -0.120396 0.3048)
			(end -0.120396 0.2794)
			(stroke
				(width 0.1)
				(type default)
			)
			(layer "B.Fab")
		)
		(fp_line
			(start -0.120396 0.2794)
			(end 0.12065 0.2794)
			(stroke
				(width 0.1)
				(type default)
			)
			(layer "B.Fab")
		)
		(fp_line
			(start -0.12065 -0.2794)
			(end -0.12065 -0.3048)
			(stroke
				(width 0.1)
				(type default)
			)
			(layer "B.Fab")
		)
		(fp_line
			(start -0.12065 -0.3048)
			(end -0.67945 -0.3048)
			(stroke
				(width 0.1)
				(type default)
			)
			(layer "B.Fab")
		)
		(fp_line
			(start -0.67945 0.3048)
			(end -0.120396 0.3048)
			(stroke
				(width 0.1)
				(type default)
			)
			(layer "B.Fab")
		)
		(fp_line
			(start -0.67945 -0.3048)
			(end -0.67945 0.3048)
			(stroke
				(width 0.1)
				(type default)
			)
			(layer "B.Fab")
		)
		(pad "1" smd circle
			(at 0.40005 0)
			(size 0 0)
			(layers "B.Cu" "B.Mask" "B.Paste")
			(net "SMB_HPDB_MISC_SCL")
		)
		(pad "2" smd circle
			(at -0.40005 0)
			(size 0 0)
			(layers "B.Cu" "B.Mask" "B.Paste")
			(net "P3V3_AUX")
		)
	)
	(footprint ""
		(layer "B.Cu")
		(at 232.029 -95.504 90)
		(property "Reference" "C28"
			(at 0 0 90)
			(layer "B.SilkS")
			(hide yes)
			(effects
				(font
					(size 1.27 1.27)
				)
				(justify mirror)
			)
		)
		(property "Value" ""
			(at 0 0 90)
			(layer "B.Fab")
			(effects
				(font
					(size 1.27 1.27)
				)
				(justify mirror)
			)
		)
		(duplicate_pad_numbers_are_jumpers no)
		(fp_line
			(start 2.2098 -0.9398)
			(end -2.2098 -0.9398)
			(stroke
				(width 0.1524)
				(type default)
			)
			(layer "B.SilkS")
		)
		(fp_line
			(start -2.2098 -0.9398)
			(end -2.2098 0.9398)
			(stroke
				(width 0.1524)
				(type default)
			)
			(layer "B.SilkS")
		)
		(fp_line
			(start 2.2098 0.9398)
			(end 2.2098 -0.9398)
			(stroke
				(width 0.1524)
				(type default)
			)
			(layer "B.SilkS")
		)
		(fp_line
			(start -2.2098 0.9398)
			(end 2.2098 0.9398)
			(stroke
				(width 0.1524)
				(type default)
			)
			(layer "B.SilkS")
		)
		(fp_line
			(start 1.700022 -0.899922)
			(end -1.700022 -0.899922)
			(stroke
				(width 0.1)
				(type default)
			)
			(layer "B.Fab")
		)
		(fp_line
			(start -1.700022 -0.899922)
			(end -1.700022 0.899922)
			(stroke
				(width 0.1)
				(type default)
			)
			(layer "B.Fab")
		)
		(fp_line
			(start 1.700022 0.899922)
			(end 1.700022 -0.899922)
			(stroke
				(width 0.1)
				(type default)
			)
			(layer "B.Fab")
		)
		(fp_line
			(start -1.700022 0.899922)
			(end 1.700022 0.899922)
			(stroke
				(width 0.1)
				(type default)
			)
			(layer "B.Fab")
		)
		(pad "1" smd rect
			(at 1.4732 0 90)
			(size 1.1684 1.5748)
			(layers "B.Cu" "B.Mask" "B.Paste")
			(net "P52V_HS")
		)
		(pad "2" smd rect
			(at -1.4732 0 90)
			(size 1.1684 1.5748)
			(layers "B.Cu" "B.Mask" "B.Paste")
			(net "GND")
		)
	)
	(footprint ""
		(layer "B.Cu")
		(at 186.309 -85.979)
		(property "Reference" "R5878"
			(at 0 0 0)
			(layer "B.SilkS")
			(hide yes)
			(effects
				(font
					(size 1.27 1.27)
				)
				(justify mirror)
			)
		)
		(property "Value" ""
			(at 0 0 0)
			(layer "B.Fab")
			(effects
				(font
					(size 1.27 1.27)
				)
				(justify mirror)
			)
		)
		(duplicate_pad_numbers_are_jumpers no)
		(fp_line
			(start -0.7874 -0.4064)
			(end -0.7874 0.4064)
			(stroke
				(width 0.1524)
				(type default)
			)
			(layer "B.SilkS")
		)
		(fp_line
			(start -0.7874 0.4064)
			(end 0.7874 0.4064)
			(stroke
				(width 0.1524)
				(type default)
			)
			(layer "B.SilkS")
		)
		(fp_line
			(start 0.7874 -0.4064)
			(end -0.7874 -0.4064)
			(stroke
				(width 0.1524)
				(type default)
			)
			(layer "B.SilkS")
		)
		(fp_line
			(start 0.7874 0.4064)
			(end 0.7874 -0.4064)
			(stroke
				(width 0.1524)
				(type default)
			)
			(layer "B.SilkS")
		)
		(fp_line
			(start -0.67945 -0.3048)
			(end -0.67945 0.3048)
			(stroke
				(width 0.1)
				(type default)
			)
			(layer "B.Fab")
		)
		(fp_line
			(start -0.67945 0.3048)
			(end -0.120396 0.3048)
			(stroke
				(width 0.1)
				(type default)
			)
			(layer "B.Fab")
		)
		(fp_line
			(start -0.12065 -0.3048)
			(end -0.67945 -0.3048)
			(stroke
				(width 0.1)
				(type default)
			)
			(layer "B.Fab")
		)
		(fp_line
			(start -0.12065 -0.2794)
			(end -0.12065 -0.3048)
			(stroke
				(width 0.1)
				(type default)
			)
			(layer "B.Fab")
		)
		(fp_line
			(start -0.120396 0.2794)
			(end 0.12065 0.2794)
			(stroke
				(width 0.1)
				(type default)
			)
			(layer "B.Fab")
		)
		(fp_line
			(start -0.120396 0.3048)
			(end -0.120396 0.2794)
			(stroke
				(width 0.1)
				(type default)
			)
			(layer "B.Fab")
		)
		(fp_line
			(start 0.12065 -0.305054)
			(end 0.12065 -0.2794)
			(stroke
				(width 0.1)
				(type default)
			)
			(layer "B.Fab")
		)
		(fp_line
			(start 0.12065 -0.2794)
			(end -0.12065 -0.2794)
			(stroke
				(width 0.1)
				(type default)
			)
			(layer "B.Fab")
		)
		(fp_line
			(start 0.12065 0.2794)
			(end 0.12065 0.3048)
			(stroke
				(width 0.1)
				(type default)
			)
			(layer "B.Fab")
		)
		(fp_line
			(start 0.12065 0.3048)
			(end 0.67945 0.3048)
			(stroke
				(width 0.1)
				(type default)
			)
			(layer "B.Fab")
		)
		(fp_line
			(start 0.67945 -0.305054)
			(end 0.12065 -0.305054)
			(stroke
				(width 0.1)
				(type default)
			)
			(layer "B.Fab")
		)
		(fp_line
			(start 0.67945 0.3048)
			(end 0.67945 -0.305054)
			(stroke
				(width 0.1)
				(type default)
			)
			(layer "B.Fab")
		)
		(pad "1" smd circle
			(at 0.40005 0 180)
			(size 0 0)
			(layers "B.Cu" "B.Mask" "B.Paste")
			(net "SMB_P52V_VPDB_SCL")
		)
		(pad "2" smd circle
			(at -0.40005 0 180)
			(size 0 0)
			(layers "B.Cu" "B.Mask" "B.Paste")
			(net "SMB_P52V_HSC_SCL")
		)
	)
	(footprint ""
		(layer "B.Cu")
		(at 238.76 -73.533 -90)
		(property "Reference" "C67"
			(at 0 0 90)
			(layer "B.SilkS")
			(hide yes)
			(effects
				(font
					(size 1.27 1.27)
				)
				(justify mirror)
			)
		)
		(property "Value" ""
			(at 0 0 90)
			(layer "B.Fab")
			(effects
				(font
					(size 1.27 1.27)
				)
				(justify mirror)
			)
		)
		(duplicate_pad_numbers_are_jumpers no)
		(fp_line
			(start -0.7874 0.4064)
			(end 0.7874 0.4064)
			(stroke
				(width 0.1524)
				(type default)
			)
			(layer "B.SilkS")
		)
		(fp_line
			(start 0.7874 0.4064)
			(end 0.7874 -0.4064)
			(stroke
				(width 0.1524)
				(type default)
			)
			(layer "B.SilkS")
		)
		(fp_line
			(start -0.7874 -0.4064)
			(end -0.7874 0.4064)
			(stroke
				(width 0.1524)
				(type default)
			)
			(layer "B.SilkS")
		)
		(fp_line
			(start 0.7874 -0.4064)
			(end -0.7874 -0.4064)
			(stroke
				(width 0.1524)
				(type default)
			)
			(layer "B.SilkS")
		)
		(fp_line
			(start -0.67945 0.3048)
			(end -0.120396 0.3048)
			(stroke
				(width 0.1)
				(type default)
			)
			(layer "B.Fab")
		)
		(fp_line
			(start -0.120396 0.3048)
			(end -0.120396 0.2794)
			(stroke
				(width 0.1)
				(type default)
			)
			(layer "B.Fab")
		)
		(fp_line
			(start 0.12065 0.3048)
			(end 0.67945 0.3048)
			(stroke
				(width 0.1)
				(type default)
			)
			(layer "B.Fab")
		)
		(fp_line
			(start 0.67945 0.3048)
			(end 0.67945 -0.305054)
			(stroke
				(width 0.1)
				(type default)
			)
			(layer "B.Fab")
		)
		(fp_line
			(start -0.120396 0.2794)
			(end 0.12065 0.2794)
			(stroke
				(width 0.1)
				(type default)
			)
			(layer "B.Fab")
		)
		(fp_line
			(start 0.12065 0.2794)
			(end 0.12065 0.3048)
			(stroke
				(width 0.1)
				(type default)
			)
			(layer "B.Fab")
		)
		(fp_line
			(start -0.12065 -0.2794)
			(end -0.12065 -0.3048)
			(stroke
				(width 0.1)
				(type default)
			)
			(layer "B.Fab")
		)
		(fp_line
			(start 0.12065 -0.2794)
			(end -0.12065 -0.2794)
			(stroke
				(width 0.1)
				(type default)
			)
			(layer "B.Fab")
		)
		(fp_line
			(start -0.67945 -0.3048)
			(end -0.67945 0.3048)
			(stroke
				(width 0.1)
				(type default)
			)
			(layer "B.Fab")
		)
		(fp_line
			(start -0.12065 -0.3048)
			(end -0.67945 -0.3048)
			(stroke
				(width 0.1)
				(type default)
			)
			(layer "B.Fab")
		)
		(fp_line
			(start 0.12065 -0.305054)
			(end 0.12065 -0.2794)
			(stroke
				(width 0.1)
				(type default)
			)
			(layer "B.Fab")
		)
		(fp_line
			(start 0.67945 -0.305054)
			(end 0.12065 -0.305054)
			(stroke
				(width 0.1)
				(type default)
			)
			(layer "B.Fab")
		)
		(pad "1" smd circle
			(at 0.40005 0 90)
			(size 0 0)
			(layers "B.Cu" "B.Mask" "B.Paste")
			(net "SMB_MB_PDB_R_SDA")
		)
		(pad "2" smd circle
			(at -0.40005 0 90)
			(size 0 0)
			(layers "B.Cu" "B.Mask" "B.Paste")
			(net "GND")
		)
	)
	(footprint ""
		(layer "B.Cu")
		(at 62.850014 -76.708 -90)
		(property "Reference" "PR78"
			(at 0 0 90)
			(layer "B.SilkS")
			(hide yes)
			(effects
				(font
					(size 1.27 1.27)
				)
				(justify mirror)
			)
		)
		(property "Value" ""
			(at 0 0 90)
			(layer "B.Fab")
			(effects
				(font
					(size 1.27 1.27)
				)
				(justify mirror)
			)
		)
		(duplicate_pad_numbers_are_jumpers no)
		(fp_line
			(start -0.7874 0.4064)
			(end 0.7874 0.4064)
			(stroke
				(width 0.1524)
				(type default)
			)
			(layer "B.SilkS")
		)
		(fp_line
			(start 0.7874 0.4064)
			(end 0.7874 -0.4064)
			(stroke
				(width 0.1524)
				(type default)
			)
			(layer "B.SilkS")
		)
		(fp_line
			(start -0.7874 -0.4064)
			(end -0.7874 0.4064)
			(stroke
				(width 0.1524)
				(type default)
			)
			(layer "B.SilkS")
		)
		(fp_line
			(start 0.7874 -0.4064)
			(end -0.7874 -0.4064)
			(stroke
				(width 0.1524)
				(type default)
			)
			(layer "B.SilkS")
		)
		(fp_line
			(start -0.67945 0.3048)
			(end -0.120396 0.3048)
			(stroke
				(width 0.1)
				(type default)
			)
			(layer "B.Fab")
		)
		(fp_line
			(start -0.120396 0.3048)
			(end -0.120396 0.2794)
			(stroke
				(width 0.1)
				(type default)
			)
			(layer "B.Fab")
		)
		(fp_line
			(start 0.12065 0.3048)
			(end 0.67945 0.3048)
			(stroke
				(width 0.1)
				(type default)
			)
			(layer "B.Fab")
		)
		(fp_line
			(start 0.67945 0.3048)
			(end 0.67945 -0.305054)
			(stroke
				(width 0.1)
				(type default)
			)
			(layer "B.Fab")
		)
		(fp_line
			(start -0.120396 0.2794)
			(end 0.12065 0.2794)
			(stroke
				(width 0.1)
				(type default)
			)
			(layer "B.Fab")
		)
		(fp_line
			(start 0.12065 0.2794)
			(end 0.12065 0.3048)
			(stroke
				(width 0.1)
				(type default)
			)
			(layer "B.Fab")
		)
		(fp_line
			(start -0.12065 -0.2794)
			(end -0.12065 -0.3048)
			(stroke
				(width 0.1)
				(type default)
			)
			(layer "B.Fab")
		)
		(fp_line
			(start 0.12065 -0.2794)
			(end -0.12065 -0.2794)
			(stroke
				(width 0.1)
				(type default)
			)
			(layer "B.Fab")
		)
		(fp_line
			(start -0.67945 -0.3048)
			(end -0.67945 0.3048)
			(stroke
				(width 0.1)
				(type default)
			)
			(layer "B.Fab")
		)
		(fp_line
			(start -0.12065 -0.3048)
			(end -0.67945 -0.3048)
			(stroke
				(width 0.1)
				(type default)
			)
			(layer "B.Fab")
		)
		(fp_line
			(start 0.12065 -0.305054)
			(end 0.12065 -0.2794)
			(stroke
				(width 0.1)
				(type default)
			)
			(layer "B.Fab")
		)
		(fp_line
			(start 0.67945 -0.305054)
			(end 0.12065 -0.305054)
			(stroke
				(width 0.1)
				(type default)
			)
			(layer "B.Fab")
		)
		(pad "1" smd rect
			(at 0.40005 0 270)
			(size 0.4572 0.508)
			(layers "B.Cu" "B.Mask" "B.Paste")
			(net "P12V_MB3_SENSE+")
		)
		(pad "2" smd rect
			(at -0.40005 0 270)
			(size 0.4572 0.508)
			(layers "B.Cu" "B.Mask" "B.Paste")
			(net "P12V_BRICK")
		)
	)
	(footprint ""
		(layer "B.Cu")
		(at 293.497 -53.34 90)
		(property "Reference" "PR4"
			(at 0 0 90)
			(layer "B.SilkS")
			(hide yes)
			(effects
				(font
					(size 1.27 1.27)
				)
				(justify mirror)
			)
		)
		(property "Value" ""
			(at 0 0 90)
			(layer "B.Fab")
			(effects
				(font
					(size 1.27 1.27)
				)
				(justify mirror)
			)
		)
		(duplicate_pad_numbers_are_jumpers no)
		(fp_line
			(start 1.651 -0.8382)
			(end -1.651 -0.8382)
			(stroke
				(width 0.1524)
				(type default)
			)
			(layer "B.SilkS")
		)
		(fp_line
			(start -1.651 -0.8382)
			(end -1.651 0.8382)
			(stroke
				(width 0.1524)
				(type default)
			)
			(layer "B.SilkS")
		)
		(fp_line
			(start 1.651 0.8382)
			(end 1.651 -0.8382)
			(stroke
				(width 0.1524)
				(type default)
			)
			(layer "B.SilkS")
		)
		(fp_line
			(start -1.651 0.8382)
			(end 1.651 0.8382)
			(stroke
				(width 0.1524)
				(type default)
			)
			(layer "B.SilkS")
		)
		(fp_line
			(start 1.559814 -0.7366)
			(end 1.559814 0.7366)
			(stroke
				(width 0.1)
				(type default)
			)
			(layer "B.Fab")
		)
		(fp_line
			(start 1.524 -0.7366)
			(end 1.559814 -0.7366)
			(stroke
				(width 0.1)
				(type default)
			)
			(layer "B.Fab")
		)
		(fp_line
			(start -1.524 -0.7366)
			(end 1.524 -0.7366)
			(stroke
				(width 0.1)
				(type default)
			)
			(layer "B.Fab")
		)
		(fp_line
			(start -1.560576 -0.7366)
			(end -1.524 -0.7366)
			(stroke
				(width 0.1)
				(type default)
			)
			(layer "B.Fab")
		)
		(fp_line
			(start 1.559814 0.7366)
			(end 1.524 0.7366)
			(stroke
				(width 0.1)
				(type default)
			)
			(layer "B.Fab")
		)
		(fp_line
			(start 1.524 0.7366)
			(end -1.524 0.7366)
			(stroke
				(width 0.1)
				(type default)
			)
			(layer "B.Fab")
		)
		(fp_line
			(start -1.524 0.7366)
			(end -1.560576 0.7366)
			(stroke
				(width 0.1)
				(type default)
			)
			(layer "B.Fab")
		)
		(fp_line
			(start -1.560576 0.7366)
			(end -1.560576 -0.7366)
			(stroke
				(width 0.1)
				(type default)
			)
			(layer "B.Fab")
		)
		(pad "1" smd rect
			(at 0.94996 0 90)
			(size 1.1176 1.3716)
			(layers "B.Cu" "B.Mask" "B.Paste")
			(net "P52V_1")
		)
		(pad "2" smd rect
			(at -0.94996 0 90)
			(size 1.1176 1.3716)
			(layers "B.Cu" "B.Mask" "B.Paste")
			(net "P52V_HS1_UVH")
		)
	)
)
